(kicad_pcb
	(version 20241229)
	(generator "pcbnew")
	(generator_version "9.0")
	(general
		(thickness 1.711)
		(legacy_teardrops no)
	)
	(paper "A4")
	(title_block
		(title "Antmicro Baseboard for Jetson AGX Thor")
		(date "2026-02-18")
		(rev "1.1.0")
		(company "Antmicro Ltd")
		(comment 1 "www.antmicro.com")
		(comment 9 "footprints 403-407 of 1170")
	)
	(layers
		(0 "F.Cu" signal)
		(4 "In1.Cu" signal)
		(6 "In2.Cu" signal)
		(8 "In3.Cu" signal)
		(10 "In4.Cu" jumper)
		(12 "In5.Cu" signal)
		(14 "In6.Cu" signal)
		(16 "In7.Cu" signal)
		(18 "In8.Cu" signal)
		(2 "B.Cu" signal)
		(9 "F.Adhes" user "F.Adhesive")
		(11 "B.Adhes" user "B.Adhesive")
		(13 "F.Paste" user)
		(15 "B.Paste" user)
		(5 "F.SilkS" user "F.Silkscreen")
		(7 "B.SilkS" user "B.Silkscreen")
		(1 "F.Mask" user)
		(3 "B.Mask" user)
		(17 "Dwgs.User" user "User.Drawings")
		(19 "Cmts.User" user "User.Comments")
		(21 "Eco1.User" user "User.Eco1")
		(23 "Eco2.User" user "User.Eco2")
		(25 "Edge.Cuts" user)
		(27 "Margin" user)
		(31 "F.CrtYd" user "F.Courtyard")
		(29 "B.CrtYd" user "B.Courtyard")
		(35 "F.Fab" user)
		(33 "B.Fab" user)
	)
	(footprint "antmicro-footprints:R_0402_1005Metric"
		(layer "F.Cu")
		(at 61.6 62.2 180)
		(descr "Resistor SMD 0402")
		(tags "resistor SMD 0402")
		(property "Reference" "R159"
			(at -1.45 -2.8 0)
			(layer "F.SilkS")
			(effects
				(font
					(size 0.7 0.7)
					(thickness 0.15)
				)
				(justify right top)
			)
		)
		(property "Value" "R_0R_0402"
			(at -1.011843 1.772046 0)
			(layer "F.Fab")
			(effects
				(font
					(size 0.7 0.7)
					(thickness 0.15)
				)
				(justify right top)
			)
		)
		(property "Datasheet" "https://industrial.panasonic.com/cdbs/www-data/pdf/RDA0000/AOA0000C301.pdf"
			(at 0 0 0)
			(layer "F.Fab")
			(hide yes)
			(effects
				(font
					(size 1.27 1.27)
					(thickness 0.15)
				)
			)
		)
		(property "Description" "SMD Chip Resistor, Jumper, 0 ohm, 100 mW, 0402 [1005 Metric], Thick Film, General Purpose"
			(at 0 0 0)
			(layer "F.Fab")
			(hide yes)
			(effects
				(font
					(size 1.27 1.27)
					(thickness 0.15)
				)
			)
		)
		(property "Manufacturer" "Panasonic"
			(at 0 0 180)
			(unlocked yes)
			(layer "F.Fab")
			(hide yes)
			(effects
				(font
					(size 1 1)
					(thickness 0.15)
				)
			)
		)
		(property "MPN" "ERJ2GE0R00X"
			(at 0 0 180)
			(unlocked yes)
			(layer "F.Fab")
			(hide yes)
			(effects
				(font
					(size 1 1)
					(thickness 0.15)
				)
			)
		)
		(property "Val" "0R"
			(at 0 0 180)
			(unlocked yes)
			(layer "F.Fab")
			(hide yes)
			(effects
				(font
					(size 1 1)
					(thickness 0.15)
				)
			)
		)
		(property "License" "Apache-2.0"
			(at 0 0 180)
			(unlocked yes)
			(layer "F.Fab")
			(hide yes)
			(effects
				(font
					(size 1 1)
					(thickness 0.15)
				)
			)
		)
		(property "Author" "Antmicro"
			(at 0 0 180)
			(unlocked yes)
			(layer "F.Fab")
			(hide yes)
			(effects
				(font
					(size 1 1)
					(thickness 0.15)
				)
			)
		)
		(property "Tolerance" "~"
			(at 0 0 180)
			(unlocked yes)
			(layer "F.Fab")
			(hide yes)
			(effects
				(font
					(size 1 1)
					(thickness 0.15)
				)
			)
		)
		(property "Current" "1A"
			(at 0 0 180)
			(unlocked yes)
			(layer "F.Fab")
			(hide yes)
			(effects
				(font
					(size 1 1)
					(thickness 0.15)
				)
			)
		)
		(sheetname "/CSI/")
		(sheetfile "csi.kicad_sch")
		(attr smd exclude_from_pos_files exclude_from_bom dnp)
		(fp_poly
			(pts
				(xy -0.925 -0.47) (xy -0.925 0.47) (xy 0.925 0.47) (xy 0.925 -0.47)
			)
			(stroke
				(width 0.05)
				(type default)
			)
			(fill no)
			(layer "F.CrtYd")
		)
		(fp_poly
			(pts
				(xy -0.5 -0.25) (xy -0.5 0.25) (xy 0.5 0.25) (xy 0.5 -0.25)
			)
			(stroke
				(width 0.15)
				(type solid)
			)
			(fill no)
			(layer "F.Fab")
		)
		(fp_text user "${REFERENCE}"
			(at -0.95 3.168 0)
			(layer "F.Fab")
			(effects
				(font
					(size 0.7 0.7)
					(thickness 0.15)
				)
				(justify right top)
			)
		)
		(fp_text user "License: Apache-2.0"
			(at -0.949999 5.169 0)
			(layer "F.Fab")
			(effects
				(font
					(size 0.7 0.7)
					(thickness 0.15)
				)
				(justify right top)
			)
		)
		(fp_text user "Author: Antmicro"
			(at -0.95 4.169 0)
			(layer "F.Fab")
			(effects
				(font
					(size 0.7 0.7)
					(thickness 0.15)
				)
				(justify right top)
			)
		)
		(pad "1" smd roundrect
			(at -0.48 0 180)
			(size 0.59 0.64)
			(layers "F.Cu" "F.Mask" "F.Paste")
			(roundrect_rratio 0.25)
			(net 980 "/CSI/I2C_MUX_A0")
			(pintype "passive")
		)
		(pad "2" smd roundrect
			(at 0.48 0 180)
			(size 0.59 0.64)
			(layers "F.Cu" "F.Mask" "F.Paste")
			(roundrect_rratio 0.25)
			(net 11 "+1V8")
			(pintype "passive")
		)
	)
	(footprint "antmicro-footprints:R_0402_1005Metric"
		(layer "F.Cu")
		(at 130.549999 63.98 180)
		(descr "Resistor SMD 0402")
		(tags "resistor SMD 0402")
		(property "Reference" "R313"
			(at 0.929999 -2.34 0)
			(layer "F.SilkS")
			(effects
				(font
					(size 0.7 0.7)
					(thickness 0.15)
				)
				(justify left bottom)
			)
		)
		(property "Value" "R_10k_0402"
			(at -1.011843 1.772046 0)
			(layer "F.Fab")
			(effects
				(font
					(size 0.7 0.7)
					(thickness 0.15)
				)
				(justify right top)
			)
		)
		(property "Datasheet" "https://www.bourns.com/docs/product-datasheets/cr.pdf"
			(at 0 0 0)
			(layer "F.Fab")
			(hide yes)
			(effects
				(font
					(size 1.27 1.27)
					(thickness 0.15)
				)
			)
		)
		(property "Description" "SMD Chip Resistor, 10 kohm, ± 1%, 62.5 mW, 0402 [1005 Metric], Thick Film, General Purpose"
			(at 0 0 0)
			(layer "F.Fab")
			(hide yes)
			(effects
				(font
					(size 1.27 1.27)
					(thickness 0.15)
				)
			)
		)
		(property "MPN" "CR0402-FX-1002GLF"
			(at 0 0 180)
			(unlocked yes)
			(layer "F.Fab")
			(hide yes)
			(effects
				(font
					(size 1 1)
					(thickness 0.15)
				)
			)
		)
		(property "Manufacturer" "Bourns"
			(at 0 0 180)
			(unlocked yes)
			(layer "F.Fab")
			(hide yes)
			(effects
				(font
					(size 1 1)
					(thickness 0.15)
				)
			)
		)
		(property "License" "Apache-2.0"
			(at 0 0 180)
			(unlocked yes)
			(layer "F.Fab")
			(hide yes)
			(effects
				(font
					(size 1 1)
					(thickness 0.15)
				)
			)
		)
		(property "Author" "Antmicro"
			(at 0 0 180)
			(unlocked yes)
			(layer "F.Fab")
			(hide yes)
			(effects
				(font
					(size 1 1)
					(thickness 0.15)
				)
			)
		)
		(property "Val" "10k"
			(at 0 0 180)
			(unlocked yes)
			(layer "F.Fab")
			(hide yes)
			(effects
				(font
					(size 1 1)
					(thickness 0.15)
				)
			)
		)
		(property "Tolerance" "1%"
			(at 0 0 180)
			(unlocked yes)
			(layer "F.Fab")
			(hide yes)
			(effects
				(font
					(size 1 1)
					(thickness 0.15)
				)
			)
		)
		(sheetname "/DCDC/")
		(sheetfile "dcdc.kicad_sch")
		(attr smd)
		(fp_poly
			(pts
				(xy -0.925 -0.47) (xy -0.925 0.47) (xy 0.925 0.47) (xy 0.925 -0.47)
			)
			(stroke
				(width 0.05)
				(type default)
			)
			(fill no)
			(layer "F.CrtYd")
		)
		(fp_poly
			(pts
				(xy -0.5 -0.25) (xy -0.5 0.25) (xy 0.5 0.25) (xy 0.5 -0.25)
			)
			(stroke
				(width 0.15)
				(type solid)
			)
			(fill no)
			(layer "F.Fab")
		)
		(fp_text user "License: Apache-2.0"
			(at -0.949999 5.169 0)
			(layer "F.Fab")
			(effects
				(font
					(size 0.7 0.7)
					(thickness 0.15)
				)
				(justify right top)
			)
		)
		(fp_text user "${REFERENCE}"
			(at -0.95 3.168 0)
			(layer "F.Fab")
			(effects
				(font
					(size 0.7 0.7)
					(thickness 0.15)
				)
				(justify right top)
			)
		)
		(fp_text user "Author: Antmicro"
			(at -0.95 4.169 0)
			(layer "F.Fab")
			(effects
				(font
					(size 0.7 0.7)
					(thickness 0.15)
				)
				(justify right top)
			)
		)
		(pad "1" smd roundrect
			(at -0.48 0 180)
			(size 0.59 0.64)
			(layers "F.Cu" "F.Mask" "F.Paste")
			(roundrect_rratio 0.25)
			(net 1 "GND")
			(pintype "passive")
		)
		(pad "2" smd roundrect
			(at 0.48 0 180)
			(size 0.59 0.64)
			(layers "F.Cu" "F.Mask" "F.Paste")
			(roundrect_rratio 0.25)
			(net 1308 "/DCDC/5V_{AON}_FB")
			(pintype "passive")
		)
	)
	(footprint "antmicro-footprints:C_0805_2012Metric"
		(layer "F.Cu")
		(at 173.19 99.81 90)
		(descr "Capacitor SMD 0805")
		(tags "capacitor SMD 0805")
		(property "Reference" "C290"
			(at -4.62 0.245 90)
			(layer "F.SilkS")
			(effects
				(font
					(size 0.7 0.7)
					(thickness 0.15)
				)
				(justify left bottom)
			)
		)
		(property "Value" "C_22u_25V_0805"
			(at -2.055717 1.963152 90)
			(layer "F.Fab")
			(effects
				(font
					(size 0.7 0.7)
					(thickness 0.15)
				)
				(justify left bottom)
			)
		)
		(property "Datasheet" "https://product.samsungsem.com/mlcc/CL21A226MAYNNN.do"
			(at 0 0 90)
			(layer "F.Fab")
			(hide yes)
			(effects
				(font
					(size 1.27 1.27)
					(thickness 0.15)
				)
			)
		)
		(property "Description" "SMT Multilayer Ceramic Capacitor, 22uF, +/-20%, 25V, X5R, 0805 [2012 Metric]"
			(at 0 0 90)
			(layer "F.Fab")
			(hide yes)
			(effects
				(font
					(size 1.27 1.27)
					(thickness 0.15)
				)
			)
		)
		(property "MPN" "CL21A226MAYNNNE"
			(at 0 0 90)
			(unlocked yes)
			(layer "F.Fab")
			(hide yes)
			(effects
				(font
					(size 1 1)
					(thickness 0.15)
				)
			)
		)
		(property "Manufacturer" "Samsung Electro-Mechanics"
			(at 0 0 90)
			(unlocked yes)
			(layer "F.Fab")
			(hide yes)
			(effects
				(font
					(size 1 1)
					(thickness 0.15)
				)
			)
		)
		(property "License" "Apache-2.0"
			(at 0 0 90)
			(unlocked yes)
			(layer "F.Fab")
			(hide yes)
			(effects
				(font
					(size 1 1)
					(thickness 0.15)
				)
			)
		)
		(property "Author" "Antmicro"
			(at 0 0 90)
			(unlocked yes)
			(layer "F.Fab")
			(hide yes)
			(effects
				(font
					(size 1 1)
					(thickness 0.15)
				)
			)
		)
		(property "Val" "22u"
			(at 0 0 90)
			(unlocked yes)
			(layer "F.Fab")
			(hide yes)
			(effects
				(font
					(size 1 1)
					(thickness 0.15)
				)
			)
		)
		(property "Voltage" "25V"
			(at 0 0 90)
			(unlocked yes)
			(layer "F.Fab")
			(hide yes)
			(effects
				(font
					(size 1 1)
					(thickness 0.15)
				)
			)
		)
		(property "Dielectric" "X5R"
			(at 0 0 90)
			(unlocked yes)
			(layer "F.Fab")
			(hide yes)
			(effects
				(font
					(size 1 1)
					(thickness 0.15)
				)
			)
		)
		(property "Public" "False"
			(at 0 0 90)
			(unlocked yes)
			(layer "F.Fab")
			(hide yes)
			(effects
				(font
					(size 1 1)
					(thickness 0.15)
				)
			)
		)
		(component_classes
			(class "DCDC_SOM")
		)
		(sheetname "/DCDC/")
		(sheetfile "dcdc.kicad_sch")
		(attr smd)
		(fp_line
			(start -0.3 -0.7)
			(end 0.3 -0.7)
			(stroke
				(width 0.15)
				(type solid)
			)
			(layer "F.SilkS")
		)
		(fp_line
			(start -0.3 0.7)
			(end 0.3 0.7)
			(stroke
				(width 0.15)
				(type solid)
			)
			(layer "F.SilkS")
		)
		(fp_rect
			(start 1.95 -0.9)
			(end -1.95 0.9)
			(stroke
				(width 0.05)
				(type default)
			)
			(fill no)
			(layer "F.CrtYd")
		)
		(fp_rect
			(start -0.95 -0.675)
			(end 0.95 0.675)
			(stroke
				(width 0.15)
				(type solid)
			)
			(fill no)
			(layer "F.Fab")
		)
		(fp_text user "License: Apache-2.0"
			(at -1.9 4.947 90)
			(layer "F.Fab")
			(effects
				(font
					(size 0.7 0.7)
					(thickness 0.15)
				)
				(justify left bottom)
			)
		)
		(fp_text user "${REFERENCE}"
			(at -1.9 3.947 90)
			(layer "F.Fab")
			(effects
				(font
					(size 0.7 0.7)
					(thickness 0.15)
				)
				(justify left bottom)
			)
		)
		(fp_text user "Author: Antmicro"
			(at -1.9 5.947 90)
			(layer "F.Fab")
			(effects
				(font
					(size 0.7 0.7)
					(thickness 0.15)
				)
				(justify left bottom)
			)
		)
		(pad "1" smd roundrect
			(at -1.1 0 90)
			(size 1.2 1.3)
			(layers "F.Cu" "F.Mask" "F.Paste")
			(roundrect_rratio 0.25)
			(net 1 "GND")
			(pintype "passive")
		)
		(pad "2" smd roundrect
			(at 1.1 0 90)
			(size 1.2 1.3)
			(layers "F.Cu" "F.Mask" "F.Paste")
			(roundrect_rratio 0.25)
			(net 903 "/DCDC/16V_OUT")
			(pintype "passive")
		)
	)
	(footprint "antmicro-footprints:C_0402_1005Metric"
		(layer "F.Cu")
		(at 184.054468 129.08 -90)
		(descr "Capacitor SMD 0402")
		(tags "capacitor SMD 0402")
		(property "Reference" "C56"
			(at 1.3 -1.35 90)
			(layer "F.SilkS")
			(effects
				(font
					(size 0.7 0.7)
					(thickness 0.15)
				)
				(justify left bottom)
			)
		)
		(property "Value" "C_4u7_25V_0402"
			(at -1.022927 2.155213 90)
			(layer "F.Fab")
			(effects
				(font
					(size 0.7 0.7)
					(thickness 0.15)
				)
				(justify right top)
			)
		)
		(property "Datasheet" "https://www.murata.com/products/productdetail?partno=GRM155C61E475ME15%23"
			(at 0 0 90)
			(layer "F.Fab")
			(hide yes)
			(effects
				(font
					(size 1.27 1.27)
					(thickness 0.15)
				)
			)
		)
		(property "Description" "SMD Multilayer Ceramic Capacitor"
			(at 0 0 90)
			(layer "F.Fab")
			(hide yes)
			(effects
				(font
					(size 1.27 1.27)
					(thickness 0.15)
				)
			)
		)
		(property "MPN" "GRM155C61E475ME15J"
			(at 0 0 270)
			(unlocked yes)
			(layer "F.Fab")
			(hide yes)
			(effects
				(font
					(size 1 1)
					(thickness 0.15)
				)
			)
		)
		(property "Manufacturer" "Murata"
			(at 0 0 270)
			(unlocked yes)
			(layer "F.Fab")
			(hide yes)
			(effects
				(font
					(size 1 1)
					(thickness 0.15)
				)
			)
		)
		(property "License" "Apache-2.0"
			(at 0 0 270)
			(unlocked yes)
			(layer "F.Fab")
			(hide yes)
			(effects
				(font
					(size 1 1)
					(thickness 0.15)
				)
			)
		)
		(property "Author" "Antmicro"
			(at 0 0 270)
			(unlocked yes)
			(layer "F.Fab")
			(hide yes)
			(effects
				(font
					(size 1 1)
					(thickness 0.15)
				)
			)
		)
		(property "Val" "4u7"
			(at 0 0 270)
			(unlocked yes)
			(layer "F.Fab")
			(hide yes)
			(effects
				(font
					(size 1 1)
					(thickness 0.15)
				)
			)
		)
		(property "Voltage" "25V"
			(at 0 0 270)
			(unlocked yes)
			(layer "F.Fab")
			(hide yes)
			(effects
				(font
					(size 1 1)
					(thickness 0.15)
				)
			)
		)
		(property "Dielectric" "X5S"
			(at 0 0 270)
			(unlocked yes)
			(layer "F.Fab")
			(hide yes)
			(effects
				(font
					(size 1 1)
					(thickness 0.15)
				)
			)
		)
		(sheetname "/DCDC/")
		(sheetfile "dcdc.kicad_sch")
		(attr smd)
		(fp_rect
			(start -0.925 -0.47)
			(end 0.925 0.47)
			(stroke
				(width 0.05)
				(type default)
			)
			(fill no)
			(layer "F.CrtYd")
		)
		(fp_line
			(start -0.494 0.248)
			(end -0.494 -0.25)
			(stroke
				(width 0.15)
				(type solid)
			)
			(layer "F.Fab")
		)
		(fp_line
			(start 0.504 0.248)
			(end -0.494 0.248)
			(stroke
				(width 0.15)
				(type solid)
			)
			(layer "F.Fab")
		)
		(fp_line
			(start -0.494 -0.25)
			(end 0.504 -0.25)
			(stroke
				(width 0.15)
				(type solid)
			)
			(layer "F.Fab")
		)
		(fp_line
			(start 0.504 -0.25)
			(end 0.504 0.248)
			(stroke
				(width 0.15)
				(type solid)
			)
			(layer "F.Fab")
		)
		(fp_text user "License: Apache-2.0"
			(at -0.939 5.799 90)
			(layer "F.Fab")
			(effects
				(font
					(size 0.7 0.7)
					(thickness 0.15)
				)
				(justify right top)
			)
		)
		(fp_text user "${REFERENCE}"
			(at -0.939 4.599 90)
			(layer "F.Fab")
			(effects
				(font
					(size 0.7 0.7)
					(thickness 0.15)
				)
				(justify right top)
			)
		)
		(fp_text user "Author: Antmicro"
			(at -0.939 3.399 90)
			(layer "F.Fab")
			(effects
				(font
					(size 0.7 0.7)
					(thickness 0.15)
				)
				(justify right top)
			)
		)
		(pad "1" smd roundrect
			(at -0.48 0 270)
			(size 0.59 0.64)
			(layers "F.Cu" "F.Mask" "F.Paste")
			(roundrect_rratio 0.25)
			(net 1 "GND")
			(pintype "passive")
		)
		(pad "2" smd roundrect
			(at 0.48 0 270)
			(size 0.59 0.64)
			(layers "F.Cu" "F.Mask" "F.Paste")
			(roundrect_rratio 0.25)
			(net 24 "/DCDC/3V3_VDRV")
			(pintype "passive")
		)
	)
	(footprint "antmicro-footprints:C_0402_1005Metric"
		(layer "F.Cu")
		(at 193.126 143.275 180)
		(descr "Capacitor SMD 0402")
		(tags "capacitor SMD 0402")
		(property "Reference" "C61"
			(at 3.226 -0.325 180)
			(layer "F.SilkS")
			(effects
				(font
					(size 0.7 0.7)
					(thickness 0.15)
				)
				(justify left bottom)
			)
		)
		(property "Value" "C_100n_0402"
			(at -1.022927 2.155213 180)
			(layer "F.Fab")
			(effects
				(font
					(size 0.7 0.7)
					(thickness 0.15)
				)
				(justify left bottom)
			)
		)
		(property "Datasheet" "https://www.murata.com/products/productdetail?partno=GRM155R61H104KE14%23"
			(at 0 0 180)
			(layer "F.Fab")
			(hide yes)
			(effects
				(font
					(size 1.27 1.27)
					(thickness 0.15)
				)
			)
		)
		(property "Description" "SMD Multilayer Ceramic Capacitor, 0.1 µF, 50 V, 0402 [1005 Metric], ± 10%, X5R, GRM Series"
			(at 0 0 180)
			(layer "F.Fab")
			(hide yes)
			(effects
				(font
					(size 1.27 1.27)
					(thickness 0.15)
				)
			)
		)
		(property "Manufacturer" "Murata"
			(at 0 0 180)
			(unlocked yes)
			(layer "F.Fab")
			(hide yes)
			(effects
				(font
					(size 1 1)
					(thickness 0.15)
				)
			)
		)
		(property "MPN" "GRM155R61H104KE14D"
			(at 0 0 180)
			(unlocked yes)
			(layer "F.Fab")
			(hide yes)
			(effects
				(font
					(size 1 1)
					(thickness 0.15)
				)
			)
		)
		(property "Val" "100n"
			(at 0 0 180)
			(unlocked yes)
			(layer "F.Fab")
			(hide yes)
			(effects
				(font
					(size 1 1)
					(thickness 0.15)
				)
			)
		)
		(property "License" "Apache-2.0"
			(at 0 0 180)
			(unlocked yes)
			(layer "F.Fab")
			(hide yes)
			(effects
				(font
					(size 1 1)
					(thickness 0.15)
				)
			)
		)
		(property "Author" "Antmicro"
			(at 0 0 180)
			(unlocked yes)
			(layer "F.Fab")
			(hide yes)
			(effects
				(font
					(size 1 1)
					(thickness 0.15)
				)
			)
		)
		(property "Voltage" "50V"
			(at 0 0 180)
			(unlocked yes)
			(layer "F.Fab")
			(hide yes)
			(effects
				(font
					(size 1 1)
					(thickness 0.15)
				)
			)
		)
		(property "Dielectric" "X5R"
			(at 0 0 180)
			(unlocked yes)
			(layer "F.Fab")
			(hide yes)
			(effects
				(font
					(size 1 1)
					(thickness 0.15)
				)
			)
		)
		(property "Public" "False"
			(at 0 0 180)
			(unlocked yes)
			(layer "F.Fab")
			(hide yes)
			(effects
				(font
					(size 1 1)
					(thickness 0.15)
				)
			)
		)
		(sheetname "/SFP/")
		(sheetfile "sfp.kicad_sch")
		(attr smd)
		(fp_rect
			(start -0.925 -0.47)
			(end 0.925 0.47)
			(stroke
				(width 0.05)
				(type default)
			)
			(fill no)
			(layer "F.CrtYd")
		)
		(fp_line
			(start 0.504 0.248)
			(end -0.494 0.248)
			(stroke
				(width 0.15)
				(type solid)
			)
			(layer "F.Fab")
		)
		(fp_line
			(start 0.504 -0.25)
			(end 0.504 0.248)
			(stroke
				(width 0.15)
				(type solid)
			)
			(layer "F.Fab")
		)
		(fp_line
			(start -0.494 0.248)
			(end -0.494 -0.25)
			(stroke
				(width 0.15)
				(type solid)
			)
			(layer "F.Fab")
		)
		(fp_line
			(start -0.494 -0.25)
			(end 0.504 -0.25)
			(stroke
				(width 0.15)
				(type solid)
			)
			(layer "F.Fab")
		)
		(fp_text user "${REFERENCE}"
			(at -0.939 4.599 180)
			(layer "F.Fab")
			(effects
				(font
					(size 0.7 0.7)
					(thickness 0.15)
				)
				(justify left bottom)
			)
		)
		(fp_text user "Author: Antmicro"
			(at -0.939 3.399 180)
			(layer "F.Fab")
			(effects
				(font
					(size 0.7 0.7)
					(thickness 0.15)
				)
				(justify left bottom)
			)
		)
		(fp_text user "License: Apache-2.0"
			(at -0.939 5.799 180)
			(layer "F.Fab")
			(effects
				(font
					(size 0.7 0.7)
					(thickness 0.15)
				)
				(justify left bottom)
			)
		)
		(pad "1" smd roundrect
			(at -0.48 0 180)
			(size 0.59 0.64)
			(layers "F.Cu" "F.Mask" "F.Paste")
			(roundrect_rratio 0.25)
			(net 27 "/SFP/SFI_CONN_RX_P")
			(pintype "passive")
		)
		(pad "2" smd roundrect
			(at 0.48 0 180)
			(size 0.59 0.64)
			(layers "F.Cu" "F.Mask" "F.Paste")
			(roundrect_rratio 0.25)
			(net 101 "/SFP/SFI.RX+")
			(pintype "passive")
		)
	)
)
